FILE_TYPE = CONNECTIVITY;
{Allegro Design Entry HDL 17.4-2019 S026 (4007227) 1/17/2022}
"PAGE_NUMBER" = 108;
0"NC";
1"GND\g";
2"GND\g";
3"P3V3\g";
4"M_L_CPU1_SB_CB<7:0>";
5"M_L_CPU1_SA_CB<7:0>";
6"M_L_CPU1_SA_CA<6:0>";
7"M_L_CPU1_SB_CA<6:0>";
8"M_L_CPU1_SA_DQ<31:0>";
9"M_L_CPU1_SB_DQ<31:0>";
10"M_L_CPU1_SA_DQS_DN<9:0>";
11"M_L_CPU1_SA_DQS_DP<9:0>";
12"M_L_CPU1_SB_DQS_DP<9:0>";
13"M_L_CPU1_SB_DQS_DN<9:0>";
14"M_L_CPU1_SA_DQ<14>";
15"M_L_CPU1_SA_DQ<15>";
16"M_L_CPU1_SB_DQS_DP<9>";
17"M_L_CPU1_SB_DQS_DN<9>";
18"M_L_CPU1_SA_DQS_DP<9>";
19"M_L_CPU1_SA_DQS_DN<9>";
20"M_L_CPU1_SA_DQS_DP<8>";
21"M_L_CPU1_SA_DQS_DN<8>";
22"M_L_CPU1_SB_DQS_DN<7>";
23"M_L_CPU1_SA_DQS_DP<7>";
24"M_L_CPU1_SB_DQS_DP<6>";
25"M_L_CPU1_SB_DQS_DN<6>";
26"M_L_CPU1_SA_DQS_DN<6>";
27"M_L_CPU1_SB_DQS_DP<5>";
28"M_L_CPU1_SB_DQS_DN<5>";
29"M_L_CPU1_SA_DQS_DP<5>";
30"M_L_CPU1_SA_DQS_DN<5>";
31"M_L_CPU1_SB_DQS_DP<4>";
32"M_L_CPU1_SB_DQS_DN<4>";
33"M_L_CPU1_SA_DQS_DP<4>";
34"M_L_CPU1_SA_DQS_DN<4>";
35"M_L_CPU1_SB_DQS_DP<3>";
36"M_L_CPU1_SB_DQS_DN<3>";
37"M_L_CPU1_SA_DQS_DP<3>";
38"M_L_CPU1_SA_DQS_DN<3>";
39"M_L_CPU1_SB_DQS_DP<2>";
40"M_L_CPU1_SB_DQS_DN<2>";
41"M_L_CPU1_SA_DQS_DP<2>";
42"M_L_CPU1_SA_DQS_DN<2>";
43"M_L_CPU1_SB_DQS_DP<1>";
44"M_L_CPU1_SB_DQS_DN<1>";
45"M_L_CPU1_SA_DQS_DP<1>";
46"M_L_CPU1_SA_DQS_DN<1>";
47"M_L_CPU1_SB_DQS_DP<0>";
48"M_L_CPU1_SB_DQS_DN<0>";
49"M_L_CPU1_SA_DQS_DP<0>";
50"M_L_CPU1_SA_DQS_DN<0>";
51"M_L_CPU1_SB_DQS_DP<7>";
52"M_L_CPU1_SB_DQS_DN<8>";
53"M_L_CPU1_SB_DQS_DP<8>";
54"M_L_CPU1_SA_DQS_DP<6>";
55"M_L_CPU1_SA_DQS_DN<7>";
56"M_L_CPU1_SA_DQ<21>";
57"M_L_CPU1_SA_DQ<22>";
58"M_L_CPU1_SA_DQ<23>";
59"M_L_CPU1_SA_DQ<24>";
60"M_L_CPU1_SA_DQ<25>";
61"M_L_CPU1_SA_DQ<26>";
62"M_L_CPU1_SA_DQ<27>";
63"M_L_CPU1_SA_DQ<28>";
64"M_L_CPU1_SA_DQ<29>";
65"M_L_CPU1_SA_DQ<30>";
66"M_L_CPU1_SA_DQ<31>";
67"M_L_CPU1_SA_PAR";
68"M_L_CPU1_SB_RSP<0>";
69"M_L_CPU1_SB_DQ<0>";
70"M_L_CPU1_SB_DQ<1>";
71"M_L_CPU1_SB_DQ<2>";
72"M_L_CPU1_SB_DQ<3>";
73"M_L_CPU1_SB_DQ<4>";
74"M_L_CPU1_SB_DQ<5>";
75"M_L_CPU1_SB_DQ<6>";
76"M_L_CPU1_SB_DQ<7>";
77"M_L_CPU1_SB_DQ<8>";
78"M_L_CPU1_SB_DQ<9>";
79"M_L_CPU1_SB_DQ<10>";
80"M_L_CPU1_SB_DQ<11>";
81"M_L_CPU1_SB_DQ<12>";
82"M_L_CPU1_SB_DQ<13>";
83"M_L_CPU1_SB_DQ<14>";
84"M_L_CPU1_SB_DQ<15>";
85"M_L_CPU1_SB_DQ<16>";
86"M_L_CPU1_SB_DQ<17>";
87"M_L_CPU1_SB_DQ<18>";
88"M_L_CPU1_SB_DQ<19>";
89"M_L_CPU1_SB_DQ<20>";
90"M_L_CPU1_SB_DQ<21>";
91"M_L_CPU1_SB_DQ<22>";
92"M_L_CPU1_SB_DQ<23>";
93"M_L_CPU1_SB_DQ<24>";
94"M_L_CPU1_SB_DQ<25>";
95"M_L_CPU1_SB_DQ<26>";
96"M_L_CPU1_SB_DQ<27>";
97"M_L_CPU1_SB_DQ<28>";
98"M_L_CPU1_SB_DQ<29>";
99"M_L_CPU1_SB_DQ<30>";
100"M_L_CPU1_SB_DQ<31>";
101"M_L_CPU1_SA_DQ<0>";
102"M_L_CPU1_SA_DQ<1>";
103"M_L_CPU1_SA_DQ<2>";
104"M_L_CPU1_SA_DQ<3>";
105"M_L_CPU1_SA_DQ<4>";
106"M_L_CPU1_SA_DQ<5>";
107"M_L_CPU1_SA_DQ<6>";
108"M_L_CPU1_SA_DQ<7>";
109"M_L_CPU1_SA_DQ<8>";
110"M_L_CPU1_SA_DQ<9>";
111"M_L_CPU1_SA_DQ<10>";
112"M_L_CPU1_SA_DQ<11>";
113"M_L_CPU1_SA_DQ<12>";
114"M_L_CPU1_SA_DQ<13>";
115"M_L_CPU1_SA_DQ<16>";
116"M_L_CPU1_SA_DQ<17>";
117"M_L_CPU1_SA_DQ<18>";
118"M_L_CPU1_SA_DQ<19>";
119"M_L_CPU1_SA_DQ<20>";
120"M_L_CPU1_SA_CS_N<1>";
121"M_L_CPU1_SB_CS_N<0>";
122"M_L_CPU1_CLK_DP<0>";
123"M_L_CPU1_CLK_DN<0>";
124"M_L_CPU1_SB_CB<0>";
125"M_L_CPU1_SB_CB<1>";
126"M_L_CPU1_SB_CB<2>";
127"M_L_CPU1_SB_CB<4>";
128"M_L_CPU1_SB_CB<5>";
129"M_L_CPU1_SB_CB<6>";
130"M_L_CPU1_SA_CB<0>";
131"M_L_CPU1_SA_CB<2>";
132"M_L_CPU1_SA_CB<3>";
133"M_L_CPU1_SA_CB<5>";
134"M_L_CPU1_SA_CB<6>";
135"M_L_CPU1_SB_CA<6>";
136"M_L_CPU1_SA_CA<6>";
137"M_L_CPU1_SB_CA<5>";
138"M_L_CPU1_SA_CA<5>";
139"M_L_CPU1_SB_CA<4>";
140"M_L_CPU1_SA_CA<4>";
141"M_L_CPU1_SB_CA<3>";
142"M_L_CPU1_SA_CA<3>";
143"M_L_CPU1_SB_CA<2>";
144"M_L_CPU1_SA_CA<2>";
145"M_L_CPU1_SB_CA<1>";
146"M_L_CPU1_SA_CA<1>";
147"M_L_CPU1_SB_CA<0>";
148"M_L_CPU1_SA_CA<0>";
149"M_L_CPU1_SB_CB<7>";
150"M_L_CPU1_SA_CB<1>";
151"M_L_CPU1_SA_CB<4>";
152"M_L_CPU1_SA_CB<7>";
153"PD_CHL_CPU1_DIMM_SAA";
154"M_L_CPU1_SB_CS_N<1>";
155"M_L_CPU1_SA_CS_N<0>";
156"M_L_CPU1_SB_PAR";
157"M_L_CPU1_SB_CB<3>";
158"M_L_CPU1_SA_RSP<0>";
159"PWRGD_CHGL_CPU1";
160"M_L_CPU1_RESET_N";
161"M_L_CPU1_ALERT_N";
162"P12V_MEM_CPU1\g";
163"GND\g";
164"GND\g";
165"GND\g";
166"I3C_SPD_DDRL_CPU1_SDA";
167"I3C_SPD_DDRL_CPU1_SCL";
168"PWRGD_CHL_CPU1_DIMM";
169"I3C_SPD_DDRGL_CPU1_SCL";
170"I3C_SPD_DDRGL_CPU1_SDA";
171"PD_CHL_CPU1_DIMM_SAA";
172"P3V3_AUX\g";
%"TAP"
"1","(-5950,4450)","0","mstr_standard","I100";
;
CDS_LIB"mstr_standard"
BODY_TYPE"PLUMBING"
HDL_TAP"TRUE";
"B \NAC \NWC"8;
"S \NAC"
BN"12"113;
%"TAP"
"1","(-5950,4400)","0","mstr_standard","I101";
;
CDS_LIB"mstr_standard"
BODY_TYPE"PLUMBING"
HDL_TAP"TRUE";
"B \NAC \NWC"8;
"S \NAC"
BN"11"112;
%"TAP"
"1","(-5950,4350)","0","mstr_standard","I102";
;
CDS_LIB"mstr_standard"
BODY_TYPE"PLUMBING"
HDL_TAP"TRUE";
"B \NAC \NWC"8;
"S \NAC"
BN"10"111;
%"TAP"
"1","(-5950,4300)","0","mstr_standard","I103";
;
CDS_LIB"mstr_standard"
BODY_TYPE"PLUMBING"
HDL_TAP"TRUE";
"B \NAC \NWC"8;
"S \NAC"
BN"9"110;
%"TAP"
"1","(-5950,4250)","0","mstr_standard","I104";
;
CDS_LIB"mstr_standard"
BODY_TYPE"PLUMBING"
HDL_TAP"TRUE";
"B \NAC \NWC"8;
"S \NAC"
BN"8"109;
%"TAP"
"1","(-5950,4600)","0","mstr_standard","I105";
;
CDS_LIB"mstr_standard"
BODY_TYPE"PLUMBING"
HDL_TAP"TRUE";
"B \NAC \NWC"8;
"S \NAC"
BN"15"15;
%"TAP"
"1","(-5950,4650)","0","mstr_standard","I106";
;
CDS_LIB"mstr_standard"
BODY_TYPE"PLUMBING"
HDL_TAP"TRUE";
"B \NAC \NWC"8;
"S \NAC"
BN"16"115;
%"TAP"
"1","(-5950,4700)","0","mstr_standard","I107";
;
CDS_LIB"mstr_standard"
BODY_TYPE"PLUMBING"
HDL_TAP"TRUE";
"B \NAC \NWC"8;
"S \NAC"
BN"17"116;
%"TAP"
"1","(-5950,4550)","0","mstr_standard","I108";
;
CDS_LIB"mstr_standard"
BODY_TYPE"PLUMBING"
HDL_TAP"TRUE";
"B \NAC \NWC"8;
"S \NAC"
BN"14"14;
%"TAP"
"1","(-5950,4500)","0","mstr_standard","I109";
;
CDS_LIB"mstr_standard"
BODY_TYPE"PLUMBING"
HDL_TAP"TRUE";
"B \NAC \NWC"8;
"S \NAC"
BN"13"114;
%"TAP"
"1","(-5950,4900)","0","mstr_standard","I110";
;
CDS_LIB"mstr_standard"
BODY_TYPE"PLUMBING"
HDL_TAP"TRUE";
"B \NAC \NWC"8;
"S \NAC"
BN"21"56;
%"TAP"
"1","(-5950,4950)","0","mstr_standard","I111";
;
CDS_LIB"mstr_standard"
BODY_TYPE"PLUMBING"
HDL_TAP"TRUE";
"B \NAC \NWC"8;
"S \NAC"
BN"22"57;
%"TAP"
"1","(-5950,4850)","0","mstr_standard","I112";
;
CDS_LIB"mstr_standard"
BODY_TYPE"PLUMBING"
HDL_TAP"TRUE";
"B \NAC \NWC"8;
"S \NAC"
BN"20"119;
%"TAP"
"1","(-5950,4800)","0","mstr_standard","I113";
;
CDS_LIB"mstr_standard"
BODY_TYPE"PLUMBING"
HDL_TAP"TRUE";
"B \NAC \NWC"8;
"S \NAC"
BN"19"118;
%"TAP"
"1","(-5950,4750)","0","mstr_standard","I114";
;
CDS_LIB"mstr_standard"
BODY_TYPE"PLUMBING"
HDL_TAP"TRUE";
"B \NAC \NWC"8;
"S \NAC"
BN"18"117;
%"TAP"
"1","(-5950,5150)","0","mstr_standard","I115";
;
CDS_LIB"mstr_standard"
BODY_TYPE"PLUMBING"
HDL_TAP"TRUE";
"B \NAC \NWC"8;
"S \NAC"
BN"26"61;
%"TAP"
"1","(-5950,5200)","0","mstr_standard","I116";
;
CDS_LIB"mstr_standard"
BODY_TYPE"PLUMBING"
HDL_TAP"TRUE";
"B \NAC \NWC"8;
"S \NAC"
BN"27"62;
%"TAP"
"1","(-5950,5100)","0","mstr_standard","I117";
;
CDS_LIB"mstr_standard"
BODY_TYPE"PLUMBING"
HDL_TAP"TRUE";
"B \NAC \NWC"8;
"S \NAC"
BN"25"60;
%"TAP"
"1","(-5950,5050)","0","mstr_standard","I118";
;
CDS_LIB"mstr_standard"
BODY_TYPE"PLUMBING"
HDL_TAP"TRUE";
"B \NAC \NWC"8;
"S \NAC"
BN"24"59;
%"TAP"
"1","(-5950,5000)","0","mstr_standard","I119";
;
CDS_LIB"mstr_standard"
BODY_TYPE"PLUMBING"
HDL_TAP"TRUE";
"B \NAC \NWC"8;
"S \NAC"
BN"23"58;
%"TAP"
"1","(-5950,5300)","0","mstr_standard","I120";
;
CDS_LIB"mstr_standard"
BODY_TYPE"PLUMBING"
HDL_TAP"TRUE";
"B \NAC \NWC"8;
"S \NAC"
BN"29"64;
%"TAP"
"1","(-5950,5400)","0","mstr_standard","I121";
;
CDS_LIB"mstr_standard"
BODY_TYPE"PLUMBING"
HDL_TAP"TRUE";
"B \NAC \NWC"8;
"S \NAC"
BN"31"66;
%"TAP"
"1","(-5950,5350)","0","mstr_standard","I122";
;
CDS_LIB"mstr_standard"
BODY_TYPE"PLUMBING"
HDL_TAP"TRUE";
"B \NAC \NWC"8;
"S \NAC"
BN"30"65;
%"TAP"
"1","(-5950,5250)","0","mstr_standard","I123";
;
CDS_LIB"mstr_standard"
BODY_TYPE"PLUMBING"
HDL_TAP"TRUE";
"B \NAC \NWC"8;
"S \NAC"
BN"28"63;
%"GND"
"1","(-6350,900)","0","mstr_symbols","I126";
;
VOLTAGE"0.0"
CDS_LIB"mstr_symbols"
SIZE"1B"
BOM_COST"MEM"
BODY_TYPE"PLUMBING"
HDL_POWER"GND";
"A\NAC"1;
%"Q_RES"
"2","(-6350,1125)","0","pure_quanta","I136";
;
LOCATION"R778"
$SEC"1"
CDS_SEC"1"
PACK_TYPE"0402LF"
VALUE"84.5K"
TOLERANCE"1%"
MATERIAL"CHIP"
WATTAGE"1/16W"
CDS_LIB"pure_quanta"
PART_NUMBER"CS38452FB05";
"A"
$PN"1"153;
"B"
$PN"2"1;
%"GND"
"1","(-2100,1900)","0","mstr_symbols","I137";
;
VOLTAGE"0.0"
SIZE"1B"
CDS_LIB"mstr_symbols"
BODY_TYPE"PLUMBING"
HDL_POWER"GND";
"A\NAC"165;
%"SCONN288_DDR506112002KQ"
"3","(-1200,3675)","0","pure_quanta","I138";
;
LOCATION"J37"
$SEC"3"
CDS_SEC"3"
MATERIAL"IO"
PART_TYPE"SMLF"
VALUE"SCONN288_DDR506112002KQ"
CDS_LIB"pure_quanta"
NEEDS_NO_SIZE"TRUE"
CDS_LMAN_SYM_OUTLINE"-450,1800,450,-1750"
PART_NUMBER"DFHST8FS479";
"G3"
$PN"G3"164;
"G2"
$PN"G2"164;
"G1"
$PN"G1"164;
"VSS62"
$PN"141"164;
"VSS61"
$PN"139"164;
"VSS60"
$PN"136"164;
"VSS58"
$PN"132"164;
"VSS104"
$PN"240"165;
"VSS102"
$PN"235"165;
"VSS100"
$PN"230"165;
"VIN_BULK2"
$PN"146"162;
"VIN_BULK1"
$PN"145"162;
"VIN_BULK0"
$PN"1"162;
"VSS126"
$PN"288"165;
"VSS125"
$PN"286"165;
"VSS124"
$PN"284"165;
"VSS123"
$PN"281"165;
"VSS122"
$PN"279"165;
"VSS121"
$PN"277"165;
"VSS120"
$PN"275"165;
"VSS119"
$PN"273"165;
"VSS118"
$PN"270"165;
"VSS117"
$PN"268"165;
"VSS116"
$PN"266"165;
"VSS115"
$PN"264"165;
"VSS114"
$PN"262"165;
"VSS113"
$PN"259"165;
"VSS112"
$PN"257"165;
"VSS111"
$PN"255"165;
"VSS110"
$PN"253"165;
"VSS109"
$PN"251"165;
"VSS108"
$PN"248"165;
"VSS107"
$PN"246"165;
"VSS106"
$PN"244"165;
"VSS105"
$PN"242"165;
"VSS103"
$PN"237"165;
"VSS101"
$PN"233"165;
"VSS99"
$PN"228"165;
"VSS98"
$PN"226"165;
"VSS97"
$PN"224"165;
"VSS96"
$PN"222"165;
"VSS95"
$PN"219"165;
"VSS94"
$PN"216"165;
"VSS93"
$PN"214"165;
"VSS92"
$PN"212"165;
"VSS91"
$PN"210"165;
"VSS90"
$PN"208"165;
"VSS89"
$PN"206"165;
"VSS88"
$PN"204"165;
"VSS87"
$PN"202"165;
"VSS86"
$PN"199"165;
"VSS85"
$PN"197"165;
"VSS84"
$PN"195"165;
"VSS83"
$PN"193"165;
"VSS82"
$PN"191"165;
"VSS81"
$PN"188"165;
"VSS80"
$PN"186"165;
"VSS79"
$PN"184"165;
"VSS78"
$PN"182"165;
"VSS77"
$PN"180"165;
"VSS76"
$PN"177"165;
"VSS75"
$PN"175"165;
"VSS74"
$PN"173"165;
"VSS73"
$PN"171"165;
"VSS72"
$PN"169"165;
"VSS71"
$PN"166"165;
"VSS70"
$PN"164"165;
"VSS69"
$PN"162"165;
"VSS68"
$PN"160"165;
"VSS67"
$PN"158"165;
"VSS66"
$PN"155"165;
"VSS65"
$PN"153"165;
"VSS64"
$PN"151"165;
"VSS63"
$PN"143"164;
"VSS59"
$PN"134"164;
"VSS57"
$PN"130"164;
"VSS56"
$PN"128"164;
"VSS55"
$PN"125"164;
"VSS54"
$PN"123"164;
"VSS53"
$PN"121"164;
"VSS52"
$PN"119"164;
"VSS51"
$PN"117"164;
"VSS50"
$PN"114"164;
"VSS49"
$PN"112"164;
"VSS48"
$PN"110"164;
"VSS47"
$PN"108"164;
"VSS46"
$PN"106"164;
"VSS45"
$PN"103"164;
"VSS44"
$PN"101"164;
"VSS43"
$PN"99"164;
"VSS42"
$PN"97"164;
"VSS41"
$PN"95"164;
"VSS40"
$PN"92"164;
"VSS39"
$PN"90"164;
"VSS38"
$PN"88"164;
"VSS37"
$PN"85"164;
"VSS36"
$PN"83"164;
"VSS35"
$PN"81"164;
"VSS34"
$PN"79"164;
"VSS33"
$PN"77"164;
"VSS32"
$PN"75"164;
"VSS31"
$PN"73"164;
"VSS30"
$PN"71"164;
"VSS29"
$PN"69"164;
"VSS28"
$PN"67"164;
"VSS27"
$PN"65"164;
"VSS26"
$PN"63"164;
"VSS25"
$PN"61"164;
"VSS24"
$PN"59"164;
"VSS23"
$PN"57"164;
"VSS22"
$PN"54"164;
"VSS21"
$PN"52"164;
"VSS20"
$PN"50"164;
"VSS19"
$PN"48"164;
"VSS18"
$PN"46"164;
"VSS17"
$PN"43"164;
"VSS16"
$PN"41"164;
"VSS15"
$PN"39"164;
"VSS14"
$PN"37"164;
"VSS13"
$PN"35"164;
"VSS12"
$PN"32"164;
"VSS11"
$PN"30"164;
"VSS10"
$PN"28"164;
"VSS9"
$PN"26"164;
"VSS8"
$PN"24"164;
"VSS7"
$PN"21"164;
"VSS6"
$PN"19"164;
"VSS5"
$PN"17"164;
"VSS4"
$PN"15"164;
"VSS3"
$PN"13"164;
"VSS2"
$PN"10"164;
"VSS1"
$PN"8"164;
"VSS0"
$PN"6"164;
%"GND"
"1","(-300,1675)","0","mstr_symbols","I139";
;
VOLTAGE"0.0"
CDS_LIB"mstr_symbols"
SIZE"1B"
BODY_TYPE"PLUMBING"
HDL_POWER"GND";
"A\NAC"164;
%"Q_CAP"
"1","(-8575,3225)","2","pure_quanta","I185";
;
LOCATION"C180"
$SEC"1"
CDS_SEC"1"
MATERIAL"X7R"
TOLERANCE"10%"
VOLTAGE"25V"
PACK_TYPE"0402"
VALUE"0.1UF"
BOM_COST"MEM"
CDS_LIB"pure_quanta"
ROOM""
PART_NUMBER"CH4104K1B00";
"B"
$PN"2"2;
"A"
$PN"1"172;
%"GND"
"1","(-8575,3000)","0","mstr_symbols","I186";
;
ROOM"MEM_EFGH_DECOUPLING_CAPS"
VOLTAGE"0"
CDS_LIB"mstr_symbols"
SIZE"1B"
BOM_COST"MEM"
BODY_TYPE"PLUMBING"
HDL_POWER"GND";
"A\NAC"2;
%"Q_RES"
"1","(-8450,2150)","2","pure_quanta","I188";
;
LOCATION"R314"
$SEC"1"
CDS_SEC"1"
VALUE"1K"
PACK_TYPE"0402LF"
MATERIAL"CHIP"
WATTAGE"1/16W"
CDS_LIB"pure_quanta"
BOM_COST"MEM"
TOLERANCE"1%"
ROOM""
PART_NUMBER"CS21002FB06";
"B"
$PN"2"159;
"A"
$PN"1"168;
%"VCC_CORE"
"1","(-8325,2475)","0","mstr_symbols","I189";
;
HDL_POWER"P3V3"
ROOM"PVCCINFAON_CPU0_CTRL"
VOLTAGE"3.3"
CDS_LIB"mstr_symbols";
"A"3;
%"Q_RES"
"2","(-8325,2300)","0","pure_quanta","I190";
;
LOCATION"R115"
$SEC"1"
CDS_SEC"1"
PACK_TYPE"0402LF"
VALUE"1K"
MATERIAL"EMPTY"
WATTAGE"1/16W"
TOLERANCE"1%"
CDS_LIB"pure_quanta"
BOM_COST"MEM"
ROOM""
PART_NUMBER"CS21002FB06";
"A"
$PN"1"3;
"B"
$PN"2"168;
%"TAP"
"1","(-3200,4275)","0","mstr_standard","I195";
;
CDS_LIB"mstr_standard"
BODY_TYPE"PLUMBING"
HDL_TAP"TRUE";
"B \NAC \NWC"10;
"S \NAC"
BN"9"19;
%"TAP"
"1","(-3200,4175)","0","mstr_standard","I196";
;
CDS_LIB"mstr_standard"
BODY_TYPE"PLUMBING"
HDL_TAP"TRUE";
"B \NAC \NWC"10;
"S \NAC"
BN"8"21;
%"TAP"
"1","(-3400,4225)","0","mstr_standard","I197";
;
CDS_LIB"mstr_standard"
BODY_TYPE"PLUMBING"
HDL_TAP"TRUE";
"B \NAC \NWC"11;
"S \NAC"
BN"8"20;
%"TAP"
"1","(-3400,4125)","0","mstr_standard","I198";
;
CDS_LIB"mstr_standard"
BODY_TYPE"PLUMBING"
HDL_TAP"TRUE";
"B \NAC \NWC"11;
"S \NAC"
BN"7"23;
%"TAP"
"1","(-3400,4325)","0","mstr_standard","I199";
;
CDS_LIB"mstr_standard"
BODY_TYPE"PLUMBING"
HDL_TAP"TRUE";
"B \NAC \NWC"11;
"S \NAC"
BN"9"18;
%"TAP"
"1","(-3200,4075)","0","mstr_standard","I200";
;
CDS_LIB"mstr_standard"
BODY_TYPE"PLUMBING"
HDL_TAP"TRUE";
"B \NAC \NWC"10;
"S \NAC"
BN"7"55;
%"TAP"
"1","(-3200,3975)","0","mstr_standard","I201";
;
CDS_LIB"mstr_standard"
BODY_TYPE"PLUMBING"
HDL_TAP"TRUE";
"B \NAC \NWC"10;
"S \NAC"
BN"6"26;
%"TAP"
"1","(-3200,3875)","0","mstr_standard","I202";
;
CDS_LIB"mstr_standard"
BODY_TYPE"PLUMBING"
HDL_TAP"TRUE";
"B \NAC \NWC"10;
"S \NAC"
BN"5"30;
%"TAP"
"1","(-3200,3775)","0","mstr_standard","I203";
;
CDS_LIB"mstr_standard"
BODY_TYPE"PLUMBING"
HDL_TAP"TRUE";
"B \NAC \NWC"10;
"S \NAC"
BN"4"34;
%"TAP"
"1","(-3200,3675)","0","mstr_standard","I204";
;
CDS_LIB"mstr_standard"
BODY_TYPE"PLUMBING"
HDL_TAP"TRUE";
"B \NAC \NWC"10;
"S \NAC"
BN"3"38;
%"TAP"
"1","(-3200,3575)","0","mstr_standard","I205";
;
CDS_LIB"mstr_standard"
BODY_TYPE"PLUMBING"
HDL_TAP"TRUE";
"B \NAC \NWC"10;
"S \NAC"
BN"2"42;
%"TAP"
"1","(-3200,3375)","0","mstr_standard","I206";
;
CDS_LIB"mstr_standard"
BODY_TYPE"PLUMBING"
HDL_TAP"TRUE";
"B \NAC \NWC"10;
"S \NAC"
BN"0"50;
%"TAP"
"1","(-3200,3475)","0","mstr_standard","I207";
;
CDS_LIB"mstr_standard"
BODY_TYPE"PLUMBING"
HDL_TAP"TRUE";
"B \NAC \NWC"10;
"S \NAC"
BN"1"46;
%"TAP"
"1","(-3200,3225)","0","mstr_standard","I208";
;
CDS_LIB"mstr_standard"
BODY_TYPE"PLUMBING"
HDL_TAP"TRUE";
"B \NAC \NWC"13;
"S \NAC"
BN"9"17;
%"TAP"
"1","(-3200,3125)","0","mstr_standard","I209";
;
CDS_LIB"mstr_standard"
BODY_TYPE"PLUMBING"
HDL_TAP"TRUE";
"B \NAC \NWC"13;
"S \NAC"
BN"8"52;
%"TAP"
"1","(-3400,3925)","0","mstr_standard","I210";
;
CDS_LIB"mstr_standard"
BODY_TYPE"PLUMBING"
HDL_TAP"TRUE";
"B \NAC \NWC"11;
"S \NAC"
BN"5"29;
%"TAP"
"1","(-3400,4025)","0","mstr_standard","I211";
;
CDS_LIB"mstr_standard"
BODY_TYPE"PLUMBING"
HDL_TAP"TRUE";
"B \NAC \NWC"11;
"S \NAC"
BN"6"54;
%"TAP"
"1","(-3400,3825)","0","mstr_standard","I212";
;
CDS_LIB"mstr_standard"
BODY_TYPE"PLUMBING"
HDL_TAP"TRUE";
"B \NAC \NWC"11;
"S \NAC"
BN"4"33;
%"TAP"
"1","(-3400,3725)","0","mstr_standard","I213";
;
CDS_LIB"mstr_standard"
BODY_TYPE"PLUMBING"
HDL_TAP"TRUE";
"B \NAC \NWC"11;
"S \NAC"
BN"3"37;
%"TAP"
"1","(-3400,3625)","0","mstr_standard","I214";
;
CDS_LIB"mstr_standard"
BODY_TYPE"PLUMBING"
HDL_TAP"TRUE";
"B \NAC \NWC"11;
"S \NAC"
BN"2"41;
%"TAP"
"1","(-3400,3425)","0","mstr_standard","I215";
;
CDS_LIB"mstr_standard"
BODY_TYPE"PLUMBING"
HDL_TAP"TRUE";
"B \NAC \NWC"11;
"S \NAC"
BN"0"49;
%"TAP"
"1","(-3400,3525)","0","mstr_standard","I216";
;
CDS_LIB"mstr_standard"
BODY_TYPE"PLUMBING"
HDL_TAP"TRUE";
"B \NAC \NWC"11;
"S \NAC"
BN"1"45;
%"TAP"
"1","(-3400,3275)","0","mstr_standard","I217";
;
CDS_LIB"mstr_standard"
BODY_TYPE"PLUMBING"
HDL_TAP"TRUE";
"B \NAC \NWC"12;
"S \NAC"
BN"9"16;
%"TAP"
"1","(-3400,3175)","0","mstr_standard","I218";
;
CDS_LIB"mstr_standard"
BODY_TYPE"PLUMBING"
HDL_TAP"TRUE";
"B \NAC \NWC"12;
"S \NAC"
BN"8"53;
%"TAP"
"1","(-3200,3025)","0","mstr_standard","I219";
;
CDS_LIB"mstr_standard"
BODY_TYPE"PLUMBING"
HDL_TAP"TRUE";
"B \NAC \NWC"13;
"S \NAC"
BN"7"22;
%"SCONN288_DDR506112002KQ"
"1","(-6800,3650)","0","pure_quanta","I22";
;
LOCATION"J37"
$SEC"1"
CDS_SEC"1"
MATERIAL"IO"
PART_TYPE"SMLF"
VALUE"SCONN288_DDR506112002KQ"
CDS_LIB"pure_quanta"
NEEDS_NO_SIZE"TRUE"
CDS_LMAN_SYM_OUTLINE"-450,1900,450,-1850"
PART_NUMBER"DFHST8FS479";
"PWR_GOOD||FAIL_N"
$PN"147"168;
"DQ31_A"
$PN"194"66;
"CB7_A"
$PN"205"152;
"CB4_A"
$PN"58"151;
"CB1_A"
$PN"53"150;
"CB7_B"
$PN"236"149;
"ALERT_N \B"
$PN"62"161;
"CA0_A"
$PN"66"148;
"CA0_B"
$PN"76"147;
"CA1_A"
$PN"211"146;
"CA1_B"
$PN"221"145;
"CA2_A"
$PN"68"144;
"CA2_B"
$PN"78"143;
"CA3_A"
$PN"213"142;
"CA3_B"
$PN"223"141;
"CA4_A"
$PN"70"140;
"CA4_B"
$PN"80"139;
"CA5_A"
$PN"215"138;
"CA5_B"
$PN"225"137;
"CA6_A"
$PN"72"136;
"CA6_B"
$PN"82"135;
"CB6_A"
$PN"203"134;
"CB5_A"
$PN"60"133;
"CB3_A"
$PN"198"132;
"CB2_A"
$PN"196"131;
"CB0_A"
$PN"51"130;
"CB6_B"
$PN"234"129;
"CB5_B"
$PN"91"128;
"CB4_B"
$PN"89"127;
"CB3_B"
$PN"243"157;
"CB2_B"
$PN"241"126;
"CB1_B"
$PN"98"125;
"CB0_B"
$PN"96"124;
"CK_C \B"
$PN"218"123;
"CK_T"
$PN"217"122;
"CS0_A_N"
$PN"64"155;
"CS0_B_N"
$PN"84"121;
"CS1_A_N"
$PN"209"120;
"CS1_B_N"
$PN"229"154;
"DQ30_A"
$PN"192"65;
"DQ29_A"
$PN"49"64;
"DQ28_A"
$PN"47"63;
"DQ27_A"
$PN"187"62;
"DQ26_A"
$PN"185"61;
"DQ25_A"
$PN"42"60;
"DQ24_A"
$PN"40"59;
"DQ23_A"
$PN"183"58;
"DQ22_A"
$PN"181"57;
"DQ21_A"
$PN"38"56;
"DQ20_A"
$PN"36"119;
"DQ19_A"
$PN"176"118;
"DQ18_A"
$PN"174"117;
"DQ17_A"
$PN"31"116;
"DQ16_A"
$PN"29"115;
"DQ15_A"
$PN"172"15;
"DQ14_A"
$PN"170"14;
"DQ13_A"
$PN"27"114;
"DQ12_A"
$PN"25"113;
"DQ11_A"
$PN"165"112;
"DQ10_A"
$PN"163"111;
"DQ9_A"
$PN"20"110;
"DQ8_A"
$PN"18"109;
"DQ7_A"
$PN"161"108;
"DQ6_A"
$PN"159"107;
"DQ5_A"
$PN"16"106;
"DQ4_A"
$PN"14"105;
"DQ3_A"
$PN"154"104;
"DQ2_A"
$PN"152"103;
"DQ1_A"
$PN"9"102;
"DQ0_A"
$PN"7"101;
"DQ31_B"
$PN"287"100;
"DQ30_B"
$PN"285"99;
"DQ29_B"
$PN"142"98;
"DQ28_B"
$PN"140"97;
"DQ27_B"
$PN"280"96;
"DQ26_B"
$PN"278"95;
"DQ25_B"
$PN"135"94;
"DQ24_B"
$PN"133"93;
"DQ23_B"
$PN"276"92;
"DQ22_B"
$PN"274"91;
"DQ21_B"
$PN"131"90;
"DQ20_B"
$PN"129"89;
"DQ19_B"
$PN"269"88;
"DQ18_B"
$PN"267"87;
"DQ17_B"
$PN"124"86;
"DQ16_B"
$PN"122"85;
"DQ15_B"
$PN"265"84;
"DQ14_B"
$PN"263"83;
"DQ13_B"
$PN"120"82;
"DQ12_B"
$PN"118"81;
"DQ11_B"
$PN"258"80;
"DQ10_B"
$PN"256"79;
"DQ9_B"
$PN"113"78;
"DQ8_B"
$PN"111"77;
"DQ7_B"
$PN"254"76;
"DQ6_B"
$PN"252"75;
"DQ5_B"
$PN"109"74;
"DQ4_B"
$PN"107"73;
"DQ3_B"
$PN"247"72;
"DQ2_B"
$PN"245"71;
"DQ1_B"
$PN"102"70;
"DQ0_B"
$PN"100"69;
"HAS"
$PN"148"171;
"HSCL"
$PN"4"167;
"HSDA"
$PN"5"166;
"LBD||RSP_A_N"
$PN"86"158;
"LBS||RSP_B_N"
$PN"87"68;
"PAR_A"
$PN"74"67;
"PAR_B"
$PN"227"156;
"RESET_N \B"
$PN"207"160;
"RFU6"
$PN"232"0;
"RFU5"
$PN"231"0;
"RFU4"
$PN"220"0;
"RFU3"
$PN"150"0;
"RFU2"
$PN"149"0;
"RFU1"
$PN"144"0;
"RFU0"
$PN"2"0;
"VIN_MGMT"
$PN"3"172;
%"TAP"
"1","(-3200,2925)","0","mstr_standard","I220";
;
CDS_LIB"mstr_standard"
BODY_TYPE"PLUMBING"
HDL_TAP"TRUE";
"B \NAC \NWC"13;
"S \NAC"
BN"6"25;
%"TAP"
"1","(-3200,2725)","0","mstr_standard","I221";
;
CDS_LIB"mstr_standard"
BODY_TYPE"PLUMBING"
HDL_TAP"TRUE";
"B \NAC \NWC"13;
"S \NAC"
BN"4"32;
%"TAP"
"1","(-3200,2825)","0","mstr_standard","I222";
;
CDS_LIB"mstr_standard"
BODY_TYPE"PLUMBING"
HDL_TAP"TRUE";
"B \NAC \NWC"13;
"S \NAC"
BN"5"28;
%"TAP"
"1","(-3200,2625)","0","mstr_standard","I223";
;
CDS_LIB"mstr_standard"
BODY_TYPE"PLUMBING"
HDL_TAP"TRUE";
"B \NAC \NWC"13;
"S \NAC"
BN"3"36;
%"TAP"
"1","(-3200,2525)","0","mstr_standard","I224";
;
CDS_LIB"mstr_standard"
BODY_TYPE"PLUMBING"
HDL_TAP"TRUE";
"B \NAC \NWC"13;
"S \NAC"
BN"2"40;
%"TAP"
"1","(-3200,2425)","0","mstr_standard","I225";
;
CDS_LIB"mstr_standard"
BODY_TYPE"PLUMBING"
HDL_TAP"TRUE";
"B \NAC \NWC"13;
"S \NAC"
BN"1"44;
%"TAP"
"1","(-3200,2325)","0","mstr_standard","I226";
;
CDS_LIB"mstr_standard"
BODY_TYPE"PLUMBING"
HDL_TAP"TRUE";
"B \NAC \NWC"13;
"S \NAC"
BN"0"48;
%"TAP"
"1","(-3400,2975)","0","mstr_standard","I227";
;
CDS_LIB"mstr_standard"
BODY_TYPE"PLUMBING"
HDL_TAP"TRUE";
"B \NAC \NWC"12;
"S \NAC"
BN"6"24;
%"TAP"
"1","(-3400,3075)","0","mstr_standard","I228";
;
CDS_LIB"mstr_standard"
BODY_TYPE"PLUMBING"
HDL_TAP"TRUE";
"B \NAC \NWC"12;
"S \NAC"
BN"7"51;
%"TAP"
"1","(-3400,2875)","0","mstr_standard","I229";
;
CDS_LIB"mstr_standard"
BODY_TYPE"PLUMBING"
HDL_TAP"TRUE";
"B \NAC \NWC"12;
"S \NAC"
BN"5"27;
%"TAP"
"1","(-7650,3200)","2","mstr_standard","I23";
;
CDS_LIB"mstr_standard"
BODY_TYPE"PLUMBING"
HDL_TAP"TRUE";
"B \NAC \NWC"4;
"S \NAC"
BN"0"124;
%"TAP"
"1","(-3400,2775)","0","mstr_standard","I230";
;
CDS_LIB"mstr_standard"
BODY_TYPE"PLUMBING"
HDL_TAP"TRUE";
"B \NAC \NWC"12;
"S \NAC"
BN"4"31;
%"TAP"
"1","(-3400,2675)","0","mstr_standard","I231";
;
CDS_LIB"mstr_standard"
BODY_TYPE"PLUMBING"
HDL_TAP"TRUE";
"B \NAC \NWC"12;
"S \NAC"
BN"3"35;
%"TAP"
"1","(-3400,2375)","0","mstr_standard","I232";
;
CDS_LIB"mstr_standard"
BODY_TYPE"PLUMBING"
HDL_TAP"TRUE";
"B \NAC \NWC"12;
"S \NAC"
BN"0"47;
%"TAP"
"1","(-3400,2575)","0","mstr_standard","I233";
;
CDS_LIB"mstr_standard"
BODY_TYPE"PLUMBING"
HDL_TAP"TRUE";
"B \NAC \NWC"12;
"S \NAC"
BN"2"39;
%"TAP"
"1","(-3400,2475)","0","mstr_standard","I234";
;
CDS_LIB"mstr_standard"
BODY_TYPE"PLUMBING"
HDL_TAP"TRUE";
"B \NAC \NWC"12;
"S \NAC"
BN"1"43;
%"SCONN288_DDR506112002KQ"
"2","(-4350,3325)","0","pure_quanta","I235";
;
LOCATION"J37"
$SEC"2"
CDS_SEC"2"
VALUE"SCONN288_DDR506112002KQ"
MATERIAL"IO"
PART_TYPE"SMLF"
CDS_LIB"pure_quanta"
NEEDS_NO_SIZE"TRUE"
CDS_LMAN_SYM_OUTLINE"-600,1150,600,-1150"
PART_NUMBER"DFHST8FS479";
"DQS7_A_C||TDQS7_A_C \B"
$PN"178"55;
"DQS6_A_T||TDQS6_A_T"
$PN"168"54;
"DQS8_B_T||TDQS8_B_T"
$PN"283"53;
"DQS8_B_C||TDQS8_B_C \B"
$PN"282"52;
"DQS7_B_T||TDQS7_B_T"
$PN"272"51;
"DQS0_A_C \B"
$PN"12"50;
"DQS0_A_T"
$PN"11"49;
"DQS0_B_C \B"
$PN"105"48;
"DQS0_B_T"
$PN"104"47;
"DQS1_A_C \B"
$PN"23"46;
"DQS1_A_T"
$PN"22"45;
"DQS1_B_C \B"
$PN"116"44;
"DQS1_B_T"
$PN"115"43;
"DQS2_A_C \B"
$PN"34"42;
"DQS2_A_T"
$PN"33"41;
"DQS2_B_C \B"
$PN"127"40;
"DQS2_B_T"
$PN"126"39;
"DQS3_A_C \B"
$PN"45"38;
"DQS3_A_T"
$PN"44"37;
"DQS3_B_C \B"
$PN"138"36;
"DQS3_B_T"
$PN"137"35;
"DQS4_A_C \B"
$PN"56"34;
"DQS4_A_T"
$PN"55"33;
"DQS4_B_C \B"
$PN"238"32;
"DQS4_B_T"
$PN"239"31;
"DQS5_A_C||TDQS5_A_C||DQS5_A_T||TDQS5_A_T \B"
$PN"156"30;
"DQS5_A_T||TDQS5_A_T"
$PN"157"29;
"DQS5_B_C||TDQS5_B_C \B"
$PN"249"28;
"DQS5_B_T||TDQS5_B_T"
$PN"250"27;
"DQS6_A_C||TDQS6_A_C||DQS6_A_T||TDQS6_A_T \B"
$PN"167"26;
"DQS6_B_C||TDQS6_B_C \B"
$PN"260"25;
"DQS6_B_T||TDQS6_B_T"
$PN"261"24;
"DQS7_A_T||TDQS7_A_T"
$PN"179"23;
"DQS7_B_C||TDQS7_B_C \B"
$PN"271"22;
"DQS8_A_C||TDQS8_A_C \B"
$PN"189"21;
"DQS8_A_T||TDQS8_A_T"
$PN"190"20;
"DQS9_A_C||TDQS9_A_C \B"
$PN"200"19;
"DQS9_A_T||TDQS9_A_T"
$PN"201"18;
"DQS9_B_C||TDQS9_B_C \B"
$PN"94"17;
"DQS9_B_T||TDQS9_B_T||DBI4_B_N"
$PN"93"16;
%"GND"
"1","(-2800,5500)","0","pure_quanta_power","I236";
;
ROOM"MEM_EFGH_DECOUPLING_CAPS"
CDS_LIB"pure_quanta_power"
BOM_COST"MEM"
SIZE"1B"
HDL_POWER"GND";
"A<SIZE-1..0>\NAC"163;
%"Q_CAP"
"1","(-2800,5850)","2","pure_quanta","I237";
;
LOCATION"C548"
$SEC"1"
CDS_SEC"1"
VOLTAGE"25V"
PACK_TYPE"C0805"
MATERIAL"X6S"
TOLERANCE"10%"
VALUE"10UF"
CDS_LIB"pure_quanta"
BOM_COST"MEM"
ROOM""
PART_NUMBER"CH6104KEA00";
"B"
$PN"2"163;
"A"
$PN"1"162;
%"Q_CAP"
"1","(-2225,5850)","2","pure_quanta","I238";
;
LOCATION"C549"
$SEC"1"
CDS_SEC"1"
MATERIAL"X6S"
TOLERANCE"10%"
VOLTAGE"25V"
PACK_TYPE"C0805"
VALUE"10UF"
CDS_LIB"pure_quanta"
BOM_COST"MEM"
ROOM""
PART_NUMBER"CH6104KEA00";
"B"
$PN"2"163;
"A"
$PN"1"162;
%"UNIVERSAL_POWER"
"1","(-2800,6175)","0","pure_quanta_power","I239";
;
HDL_POWER"P12V_MEM_CPU1"
CDS_LIB"pure_quanta_power";
"A"162;
%"TAP"
"1","(-7650,3250)","2","mstr_standard","I24";
;
CDS_LIB"mstr_standard"
BODY_TYPE"PLUMBING"
HDL_TAP"TRUE";
"B \NAC \NWC"4;
"S \NAC"
BN"1"125;
%"Q_RES"
"1","(-7700,2625)","0","pure_quanta","I241";
;
LOCATION"R1591"
$SEC"1"
CDS_SEC"1"
VALUE"49.9"
TOLERANCE"1%"
WATTAGE"1/16W"
PACK_TYPE"0402LF"
MATERIAL"CHIP"
CDS_LIB"pure_quanta"
PART_NUMBER"CS04992FB07";
"B"
$PN"2"167;
"A"
$PN"1"169;
%"Q_RES"
"1","(-8075,2850)","0","pure_quanta","I242";
;
LOCATION"R1711"
$SEC"1"
CDS_SEC"1"
MATERIAL"CHIP"
PACK_TYPE"0402LF"
VALUE"10"
TOLERANCE"1%"
WATTAGE"1/16W"
CDS_LIB"pure_quanta"
PART_NUMBER"CS01002FB07";
"B"
$PN"2"166;
"A"
$PN"1"170;
%"TAP"
"1","(-7650,3300)","2","mstr_standard","I25";
;
CDS_LIB"mstr_standard"
BODY_TYPE"PLUMBING"
HDL_TAP"TRUE";
"B \NAC \NWC"4;
"S \NAC"
BN"2"126;
%"TAP"
"1","(-7650,3400)","2","mstr_standard","I26";
;
CDS_LIB"mstr_standard"
BODY_TYPE"PLUMBING"
HDL_TAP"TRUE";
"B \NAC \NWC"4;
"S \NAC"
BN"4"127;
%"TAP"
"1","(-7650,3350)","2","mstr_standard","I27";
;
CDS_LIB"mstr_standard"
BODY_TYPE"PLUMBING"
HDL_TAP"TRUE";
"B \NAC \NWC"4;
"S \NAC"
BN"3"157;
%"TAP"
"1","(-7650,3450)","2","mstr_standard","I28";
;
CDS_LIB"mstr_standard"
BODY_TYPE"PLUMBING"
HDL_TAP"TRUE";
"B \NAC \NWC"4;
"S \NAC"
BN"5"128;
%"TAP"
"1","(-7650,3550)","2","mstr_standard","I29";
;
CDS_LIB"mstr_standard"
BODY_TYPE"PLUMBING"
HDL_TAP"TRUE";
"B \NAC \NWC"4;
"S \NAC"
BN"7"149;
%"TAP"
"1","(-7650,3650)","2","mstr_standard","I30";
;
CDS_LIB"mstr_standard"
BODY_TYPE"PLUMBING"
HDL_TAP"TRUE";
"B \NAC \NWC"5;
"S \NAC"
BN"0"130;
%"TAP"
"1","(-7650,3500)","2","mstr_standard","I31";
;
CDS_LIB"mstr_standard"
BODY_TYPE"PLUMBING"
HDL_TAP"TRUE";
"B \NAC \NWC"4;
"S \NAC"
BN"6"129;
%"TAP"
"1","(-5950,2300)","0","mstr_standard","I32";
;
CDS_LIB"mstr_standard"
BODY_TYPE"PLUMBING"
HDL_TAP"TRUE";
"B \NAC \NWC"9;
"S \NAC"
BN"2"71;
%"TAP"
"1","(-5950,2350)","0","mstr_standard","I33";
;
CDS_LIB"mstr_standard"
BODY_TYPE"PLUMBING"
HDL_TAP"TRUE";
"B \NAC \NWC"9;
"S \NAC"
BN"3"72;
%"TAP"
"1","(-5950,2400)","0","mstr_standard","I34";
;
CDS_LIB"mstr_standard"
BODY_TYPE"PLUMBING"
HDL_TAP"TRUE";
"B \NAC \NWC"9;
"S \NAC"
BN"4"73;
%"TAP"
"1","(-5950,2250)","0","mstr_standard","I35";
;
CDS_LIB"mstr_standard"
BODY_TYPE"PLUMBING"
HDL_TAP"TRUE";
"B \NAC \NWC"9;
"S \NAC"
BN"1"70;
%"TAP"
"1","(-5950,2200)","0","mstr_standard","I36";
;
CDS_LIB"mstr_standard"
BODY_TYPE"PLUMBING"
HDL_TAP"TRUE";
"B \NAC \NWC"9;
"S \NAC"
BN"0"69;
%"TAP"
"1","(-5950,2550)","0","mstr_standard","I37";
;
CDS_LIB"mstr_standard"
BODY_TYPE"PLUMBING"
HDL_TAP"TRUE";
"B \NAC \NWC"9;
"S \NAC"
BN"7"76;
%"TAP"
"1","(-5950,2650)","0","mstr_standard","I38";
;
CDS_LIB"mstr_standard"
BODY_TYPE"PLUMBING"
HDL_TAP"TRUE";
"B \NAC \NWC"9;
"S \NAC"
BN"9"78;
%"TAP"
"1","(-5950,2600)","0","mstr_standard","I39";
;
CDS_LIB"mstr_standard"
BODY_TYPE"PLUMBING"
HDL_TAP"TRUE";
"B \NAC \NWC"9;
"S \NAC"
BN"8"77;
%"TAP"
"1","(-5950,2500)","0","mstr_standard","I40";
;
CDS_LIB"mstr_standard"
BODY_TYPE"PLUMBING"
HDL_TAP"TRUE";
"B \NAC \NWC"9;
"S \NAC"
BN"6"75;
%"TAP"
"1","(-5950,2450)","0","mstr_standard","I41";
;
CDS_LIB"mstr_standard"
BODY_TYPE"PLUMBING"
HDL_TAP"TRUE";
"B \NAC \NWC"9;
"S \NAC"
BN"5"74;
%"TAP"
"1","(-5950,2850)","0","mstr_standard","I42";
;
CDS_LIB"mstr_standard"
BODY_TYPE"PLUMBING"
HDL_TAP"TRUE";
"B \NAC \NWC"9;
"S \NAC"
BN"13"82;
%"TAP"
"1","(-5950,2900)","0","mstr_standard","I43";
;
CDS_LIB"mstr_standard"
BODY_TYPE"PLUMBING"
HDL_TAP"TRUE";
"B \NAC \NWC"9;
"S \NAC"
BN"14"83;
%"TAP"
"1","(-5950,2800)","0","mstr_standard","I44";
;
CDS_LIB"mstr_standard"
BODY_TYPE"PLUMBING"
HDL_TAP"TRUE";
"B \NAC \NWC"9;
"S \NAC"
BN"12"81;
%"TAP"
"1","(-5950,2750)","0","mstr_standard","I45";
;
CDS_LIB"mstr_standard"
BODY_TYPE"PLUMBING"
HDL_TAP"TRUE";
"B \NAC \NWC"9;
"S \NAC"
BN"11"80;
%"TAP"
"1","(-5950,2700)","0","mstr_standard","I46";
;
CDS_LIB"mstr_standard"
BODY_TYPE"PLUMBING"
HDL_TAP"TRUE";
"B \NAC \NWC"9;
"S \NAC"
BN"10"79;
%"TAP"
"1","(-5950,3100)","0","mstr_standard","I47";
;
CDS_LIB"mstr_standard"
BODY_TYPE"PLUMBING"
HDL_TAP"TRUE";
"B \NAC \NWC"9;
"S \NAC"
BN"18"87;
%"TAP"
"1","(-5950,3150)","0","mstr_standard","I48";
;
CDS_LIB"mstr_standard"
BODY_TYPE"PLUMBING"
HDL_TAP"TRUE";
"B \NAC \NWC"9;
"S \NAC"
BN"19"88;
%"TAP"
"1","(-5950,3050)","0","mstr_standard","I49";
;
CDS_LIB"mstr_standard"
BODY_TYPE"PLUMBING"
HDL_TAP"TRUE";
"B \NAC \NWC"9;
"S \NAC"
BN"17"86;
%"VCC_CORE"
"1","(-8475,3425)","0","mstr_symbols","I5";
;
HDL_POWER"P3V3_AUX"
ROOM"PVCCINFAON_CPU1_CTRL"
VOLTAGE"3.3"
CDS_LIB"mstr_symbols";
"A"172;
%"TAP"
"1","(-5950,3000)","0","mstr_standard","I50";
;
CDS_LIB"mstr_standard"
BODY_TYPE"PLUMBING"
HDL_TAP"TRUE";
"B \NAC \NWC"9;
"S \NAC"
BN"16"85;
%"TAP"
"1","(-5950,2950)","0","mstr_standard","I51";
;
CDS_LIB"mstr_standard"
BODY_TYPE"PLUMBING"
HDL_TAP"TRUE";
"B \NAC \NWC"9;
"S \NAC"
BN"15"84;
%"TAP"
"1","(-5950,3350)","0","mstr_standard","I52";
;
CDS_LIB"mstr_standard"
BODY_TYPE"PLUMBING"
HDL_TAP"TRUE";
"B \NAC \NWC"9;
"S \NAC"
BN"23"92;
%"TAP"
"1","(-5950,3400)","0","mstr_standard","I53";
;
CDS_LIB"mstr_standard"
BODY_TYPE"PLUMBING"
HDL_TAP"TRUE";
"B \NAC \NWC"9;
"S \NAC"
BN"24"93;
%"TAP"
"1","(-5950,3300)","0","mstr_standard","I54";
;
CDS_LIB"mstr_standard"
BODY_TYPE"PLUMBING"
HDL_TAP"TRUE";
"B \NAC \NWC"9;
"S \NAC"
BN"22"91;
%"TAP"
"1","(-5950,3250)","0","mstr_standard","I55";
;
CDS_LIB"mstr_standard"
BODY_TYPE"PLUMBING"
HDL_TAP"TRUE";
"B \NAC \NWC"9;
"S \NAC"
BN"21"90;
%"TAP"
"1","(-5950,3200)","0","mstr_standard","I56";
;
CDS_LIB"mstr_standard"
BODY_TYPE"PLUMBING"
HDL_TAP"TRUE";
"B \NAC \NWC"9;
"S \NAC"
BN"20"89;
%"TAP"
"1","(-5950,3600)","0","mstr_standard","I57";
;
CDS_LIB"mstr_standard"
BODY_TYPE"PLUMBING"
HDL_TAP"TRUE";
"B \NAC \NWC"9;
"S \NAC"
BN"28"97;
%"TAP"
"1","(-5950,3650)","0","mstr_standard","I58";
;
CDS_LIB"mstr_standard"
BODY_TYPE"PLUMBING"
HDL_TAP"TRUE";
"B \NAC \NWC"9;
"S \NAC"
BN"29"98;
%"TAP"
"1","(-5950,3550)","0","mstr_standard","I59";
;
CDS_LIB"mstr_standard"
BODY_TYPE"PLUMBING"
HDL_TAP"TRUE";
"B \NAC \NWC"9;
"S \NAC"
BN"27"96;
%"TAP"
"1","(-5950,3500)","0","mstr_standard","I60";
;
CDS_LIB"mstr_standard"
BODY_TYPE"PLUMBING"
HDL_TAP"TRUE";
"B \NAC \NWC"9;
"S \NAC"
BN"26"95;
%"TAP"
"1","(-5950,3450)","0","mstr_standard","I61";
;
CDS_LIB"mstr_standard"
BODY_TYPE"PLUMBING"
HDL_TAP"TRUE";
"B \NAC \NWC"9;
"S \NAC"
BN"25"94;
%"TAP"
"1","(-7650,3700)","2","mstr_standard","I69";
;
CDS_LIB"mstr_standard"
BODY_TYPE"PLUMBING"
HDL_TAP"TRUE";
"B \NAC \NWC"5;
"S \NAC"
BN"1"150;
%"TAP"
"1","(-7650,3750)","2","mstr_standard","I70";
;
CDS_LIB"mstr_standard"
BODY_TYPE"PLUMBING"
HDL_TAP"TRUE";
"B \NAC \NWC"5;
"S \NAC"
BN"2"131;
%"TAP"
"1","(-7650,3800)","2","mstr_standard","I71";
;
CDS_LIB"mstr_standard"
BODY_TYPE"PLUMBING"
HDL_TAP"TRUE";
"B \NAC \NWC"5;
"S \NAC"
BN"3"132;
%"TAP"
"1","(-7650,3900)","2","mstr_standard","I72";
;
CDS_LIB"mstr_standard"
BODY_TYPE"PLUMBING"
HDL_TAP"TRUE";
"B \NAC \NWC"5;
"S \NAC"
BN"5"133;
%"TAP"
"1","(-7650,3850)","2","mstr_standard","I73";
;
CDS_LIB"mstr_standard"
BODY_TYPE"PLUMBING"
HDL_TAP"TRUE";
"B \NAC \NWC"5;
"S \NAC"
BN"4"151;
%"TAP"
"1","(-7650,3950)","2","mstr_standard","I74";
;
CDS_LIB"mstr_standard"
BODY_TYPE"PLUMBING"
HDL_TAP"TRUE";
"B \NAC \NWC"5;
"S \NAC"
BN"6"134;
%"TAP"
"1","(-7650,4000)","2","mstr_standard","I75";
;
CDS_LIB"mstr_standard"
BODY_TYPE"PLUMBING"
HDL_TAP"TRUE";
"B \NAC \NWC"5;
"S \NAC"
BN"7"152;
%"TAP"
"1","(-7650,4700)","2","mstr_standard","I76";
;
CDS_LIB"mstr_standard"
BODY_TYPE"PLUMBING"
HDL_TAP"TRUE";
"B \NAC \NWC"7;
"S \NAC"
BN"0"147;
%"TAP"
"1","(-7650,4800)","2","mstr_standard","I77";
;
CDS_LIB"mstr_standard"
BODY_TYPE"PLUMBING"
HDL_TAP"TRUE";
"B \NAC \NWC"7;
"S \NAC"
BN"2"143;
%"TAP"
"1","(-7650,4750)","2","mstr_standard","I78";
;
CDS_LIB"mstr_standard"
BODY_TYPE"PLUMBING"
HDL_TAP"TRUE";
"B \NAC \NWC"7;
"S \NAC"
BN"1"145;
%"TAP"
"1","(-7650,4850)","2","mstr_standard","I79";
;
CDS_LIB"mstr_standard"
BODY_TYPE"PLUMBING"
HDL_TAP"TRUE";
"B \NAC \NWC"7;
"S \NAC"
BN"3"141;
%"TAP"
"1","(-7650,4900)","2","mstr_standard","I80";
;
CDS_LIB"mstr_standard"
BODY_TYPE"PLUMBING"
HDL_TAP"TRUE";
"B \NAC \NWC"7;
"S \NAC"
BN"4"139;
%"TAP"
"1","(-7650,4950)","2","mstr_standard","I81";
;
CDS_LIB"mstr_standard"
BODY_TYPE"PLUMBING"
HDL_TAP"TRUE";
"B \NAC \NWC"7;
"S \NAC"
BN"5"137;
%"TAP"
"1","(-7650,5150)","2","mstr_standard","I82";
;
CDS_LIB"mstr_standard"
BODY_TYPE"PLUMBING"
HDL_TAP"TRUE";
"B \NAC \NWC"6;
"S \NAC"
BN"1"146;
%"TAP"
"1","(-7650,5200)","2","mstr_standard","I83";
;
CDS_LIB"mstr_standard"
BODY_TYPE"PLUMBING"
HDL_TAP"TRUE";
"B \NAC \NWC"6;
"S \NAC"
BN"2"144;
%"TAP"
"1","(-7650,5100)","2","mstr_standard","I84";
;
CDS_LIB"mstr_standard"
BODY_TYPE"PLUMBING"
HDL_TAP"TRUE";
"B \NAC \NWC"6;
"S \NAC"
BN"0"148;
%"TAP"
"1","(-7650,5000)","2","mstr_standard","I85";
;
CDS_LIB"mstr_standard"
BODY_TYPE"PLUMBING"
HDL_TAP"TRUE";
"B \NAC \NWC"7;
"S \NAC"
BN"6"135;
%"TAP"
"1","(-7650,5250)","2","mstr_standard","I86";
;
CDS_LIB"mstr_standard"
BODY_TYPE"PLUMBING"
HDL_TAP"TRUE";
"B \NAC \NWC"6;
"S \NAC"
BN"3"142;
%"TAP"
"1","(-7650,5300)","2","mstr_standard","I87";
;
CDS_LIB"mstr_standard"
BODY_TYPE"PLUMBING"
HDL_TAP"TRUE";
"B \NAC \NWC"6;
"S \NAC"
BN"4"140;
%"TAP"
"1","(-7650,5350)","2","mstr_standard","I88";
;
CDS_LIB"mstr_standard"
BODY_TYPE"PLUMBING"
HDL_TAP"TRUE";
"B \NAC \NWC"6;
"S \NAC"
BN"5"138;
%"TAP"
"1","(-7650,5400)","2","mstr_standard","I89";
;
CDS_LIB"mstr_standard"
BODY_TYPE"PLUMBING"
HDL_TAP"TRUE";
"B \NAC \NWC"6;
"S \NAC"
BN"6"136;
%"TAP"
"1","(-5950,3850)","0","mstr_standard","I90";
;
CDS_LIB"mstr_standard"
BODY_TYPE"PLUMBING"
HDL_TAP"TRUE";
"B \NAC \NWC"8;
"S \NAC"
BN"0"101;
%"TAP"
"1","(-5950,3900)","0","mstr_standard","I91";
;
CDS_LIB"mstr_standard"
BODY_TYPE"PLUMBING"
HDL_TAP"TRUE";
"B \NAC \NWC"8;
"S \NAC"
BN"1"102;
%"TAP"
"1","(-5950,3950)","0","mstr_standard","I92";
;
CDS_LIB"mstr_standard"
BODY_TYPE"PLUMBING"
HDL_TAP"TRUE";
"B \NAC \NWC"8;
"S \NAC"
BN"2"103;
%"TAP"
"1","(-5950,3750)","0","mstr_standard","I93";
;
CDS_LIB"mstr_standard"
BODY_TYPE"PLUMBING"
HDL_TAP"TRUE";
"B \NAC \NWC"9;
"S \NAC"
BN"31"100;
%"TAP"
"1","(-5950,3700)","0","mstr_standard","I94";
;
CDS_LIB"mstr_standard"
BODY_TYPE"PLUMBING"
HDL_TAP"TRUE";
"B \NAC \NWC"9;
"S \NAC"
BN"30"99;
%"TAP"
"1","(-5950,4100)","0","mstr_standard","I95";
;
CDS_LIB"mstr_standard"
BODY_TYPE"PLUMBING"
HDL_TAP"TRUE";
"B \NAC \NWC"8;
"S \NAC"
BN"5"106;
%"TAP"
"1","(-5950,4200)","0","mstr_standard","I96";
;
CDS_LIB"mstr_standard"
BODY_TYPE"PLUMBING"
HDL_TAP"TRUE";
"B \NAC \NWC"8;
"S \NAC"
BN"7"108;
%"TAP"
"1","(-5950,4150)","0","mstr_standard","I97";
;
CDS_LIB"mstr_standard"
BODY_TYPE"PLUMBING"
HDL_TAP"TRUE";
"B \NAC \NWC"8;
"S \NAC"
BN"6"107;
%"TAP"
"1","(-5950,4050)","0","mstr_standard","I98";
;
CDS_LIB"mstr_standard"
BODY_TYPE"PLUMBING"
HDL_TAP"TRUE";
"B \NAC \NWC"8;
"S \NAC"
BN"4"105;
%"TAP"
"1","(-5950,4000)","0","mstr_standard","I99";
;
CDS_LIB"mstr_standard"
BODY_TYPE"PLUMBING"
HDL_TAP"TRUE";
"B \NAC \NWC"8;
"S \NAC"
BN"3"104;
END.
